# T6G (Grand Teton) — schematic netlist excerpt (pin names and nets, part order shuffled) for the footprints in the layout excerpt that follows; sources: Cadence DE-HDL packaged netlist, KiCad conversion of 04192023_DAF0TMB3IC0_F0TG_MB_C_brd_V02_OCP.brd

R1626  Q_RES  1K 1% CHIP  pkg 0402LF  page 172 : A = PVDD18_S5_P0 ; B = HDT_HDR_TMS
PC177_3  Q_CAP  0.1UF 25V 10% X7R  pkg 0402  page 206 : A = SW_P12V_AUX_PVDDIO_P0_FLT ; B = GND

(kicad_pcb
	(version 20260206)
	(generator "pcbnew")
	(generator_version "10.0")
	(general
		(thickness 1.6)
		(legacy_teardrops no)
	)
	(paper "A4")
	(title_block
		(title "04192023_DAF0TMB3IC0_F0TG_MB_C_brd_V02_OCP.brd")
		(comment 1 "Grand Teton / footprints 251-252 of 8354")
	)
	(layers
		(0 "F.Cu" signal "TOP")
		(4 "In1.Cu" signal "GND")
		(6 "In2.Cu" signal "IN1")
		(8 "In3.Cu" signal "GND1")
		(10 "In4.Cu" signal "IN2")
		(12 "In5.Cu" signal "GND2")
		(14 "In6.Cu" signal "IN3")
		(16 "In7.Cu" signal "GND3")
		(18 "In8.Cu" signal "VCC")
		(20 "In9.Cu" signal "VCC1")
		(22 "In10.Cu" signal "GND4")
		(24 "In11.Cu" signal "IN4")
		(26 "In12.Cu" signal "GND5")
		(28 "In13.Cu" signal "IN5")
		(30 "In14.Cu" signal "GND6")
		(32 "In15.Cu" signal "IN6")
		(34 "In16.Cu" signal "GND7")
		(2 "B.Cu" signal "BOTTOM")
		(9 "F.Adhes" user "F.Adhesive")
		(11 "B.Adhes" user "B.Adhesive")
		(13 "F.Paste" user "Package Geometry/Pastemask Top")
		(15 "B.Paste" user "Package Geometry/Pastemask Bottom")
		(5 "F.SilkS" user "Ref Des/Silkscreen Top")
		(7 "B.SilkS" user "Ref Des/Silkscreen Bottom")
		(1 "F.Mask" user "Board Geometry/Soldermask Top")
		(3 "B.Mask" user "Board Geometry/Soldermask Bottom")
		(17 "Dwgs.User" user "User.Drawings")
		(19 "Cmts.User" user "User.Comments")
		(21 "Eco1.User" user "User.Eco1")
		(23 "Eco2.User" user "User.Eco2")
		(25 "Edge.Cuts" user "Board Geometry/Outline")
		(27 "Margin" user)
		(31 "F.CrtYd" user "Package Geometry/Place Bound Top")
		(29 "B.CrtYd" user "Package Geometry/Place Bound Bottom")
		(35 "F.Fab" user "Ref Des/Assembly Top")
		(33 "B.Fab" user "Ref Des/Assembly Bottom")
	)
	(footprint ""
		(layer "F.Cu")
		(at 384.465576 -54.56555 -90)
		(property "Reference" "R1626"
			(at 0 0 270)
			(layer "F.SilkS")
			(hide yes)
			(effects
				(font
					(size 1.27 1.27)
				)
			)
		)
		(property "Value" ""
			(at 0 0 270)
			(layer "F.Fab")
			(effects
				(font
					(size 1.27 1.27)
				)
			)
		)
		(duplicate_pad_numbers_are_jumpers no)
		(fp_line
			(start -0.7874 0.4064)
			(end -0.7874 -0.4064)
			(stroke
				(width 0.1524)
				(type default)
			)
			(layer "F.SilkS")
		)
		(fp_line
			(start 0.7874 0.4064)
			(end -0.7874 0.4064)
			(stroke
				(width 0.1524)
				(type default)
			)
			(layer "F.SilkS")
		)
		(fp_line
			(start -0.7874 -0.4064)
			(end 0.7874 -0.4064)
			(stroke
				(width 0.1524)
				(type default)
			)
			(layer "F.SilkS")
		)
		(fp_line
			(start 0.7874 -0.4064)
			(end 0.7874 0.4064)
			(stroke
				(width 0.1524)
				(type default)
			)
			(layer "F.SilkS")
		)
		(fp_line
			(start -0.67945 0.3048)
			(end -0.67945 -0.305054)
			(stroke
				(width 0.1)
				(type default)
			)
			(layer "F.Fab")
		)
		(fp_line
			(start -0.12065 0.3048)
			(end -0.67945 0.3048)
			(stroke
				(width 0.1)
				(type default)
			)
			(layer "F.Fab")
		)
		(fp_line
			(start 0.120396 0.3048)
			(end 0.120396 0.2794)
			(stroke
				(width 0.1)
				(type default)
			)
			(layer "F.Fab")
		)
		(fp_line
			(start 0.67945 0.3048)
			(end 0.120396 0.3048)
			(stroke
				(width 0.1)
				(type default)
			)
			(layer "F.Fab")
		)
		(fp_line
			(start -0.12065 0.2794)
			(end -0.12065 0.3048)
			(stroke
				(width 0.1)
				(type default)
			)
			(layer "F.Fab")
		)
		(fp_line
			(start 0.120396 0.2794)
			(end -0.12065 0.2794)
			(stroke
				(width 0.1)
				(type default)
			)
			(layer "F.Fab")
		)
		(fp_line
			(start -0.12065 -0.2794)
			(end 0.12065 -0.2794)
			(stroke
				(width 0.1)
				(type default)
			)
			(layer "F.Fab")
		)
		(fp_line
			(start 0.12065 -0.2794)
			(end 0.12065 -0.3048)
			(stroke
				(width 0.1)
				(type default)
			)
			(layer "F.Fab")
		)
		(fp_line
			(start 0.12065 -0.3048)
			(end 0.67945 -0.3048)
			(stroke
				(width 0.1)
				(type default)
			)
			(layer "F.Fab")
		)
		(fp_line
			(start 0.67945 -0.3048)
			(end 0.67945 0.3048)
			(stroke
				(width 0.1)
				(type default)
			)
			(layer "F.Fab")
		)
		(fp_line
			(start -0.67945 -0.305054)
			(end -0.12065 -0.305054)
			(stroke
				(width 0.1)
				(type default)
			)
			(layer "F.Fab")
		)
		(fp_line
			(start -0.12065 -0.305054)
			(end -0.12065 -0.2794)
			(stroke
				(width 0.1)
				(type default)
			)
			(layer "F.Fab")
		)
		(pad "1" smd circle
			(at -0.40005 0 270)
			(size 0 0)
			(layers "F.Cu" "F.Mask" "F.Paste")
			(net "PVDD18_S5_P0")
		)
		(pad "2" smd circle
			(at 0.40005 0 270)
			(size 0 0)
			(layers "F.Cu" "F.Mask" "F.Paste")
			(net "HDT_HDR_TMS")
		)
	)
	(footprint ""
		(layer "F.Cu")
		(at 279.56637 -351.100644)
		(property "Reference" "PC177_3"
			(at 0 0 0)
			(layer "F.SilkS")
			(hide yes)
			(effects
				(font
					(size 1.27 1.27)
				)
			)
		)
		(property "Value" ""
			(at 0 0 0)
			(layer "F.Fab")
			(effects
				(font
					(size 1.27 1.27)
				)
			)
		)
		(duplicate_pad_numbers_are_jumpers no)
		(fp_line
			(start -0.7874 -0.4064)
			(end 0.7874 -0.4064)
			(stroke
				(width 0.1524)
				(type default)
			)
			(layer "F.SilkS")
		)
		(fp_line
			(start -0.7874 0.4064)
			(end -0.7874 -0.4064)
			(stroke
				(width 0.1524)
				(type default)
			)
			(layer "F.SilkS")
		)
		(fp_line
			(start 0.7874 -0.4064)
			(end 0.7874 0.4064)
			(stroke
				(width 0.1524)
				(type default)
			)
			(layer "F.SilkS")
		)
		(fp_line
			(start 0.7874 0.4064)
			(end -0.7874 0.4064)
			(stroke
				(width 0.1524)
				(type default)
			)
			(layer "F.SilkS")
		)
		(fp_line
			(start -0.67945 -0.305054)
			(end -0.12065 -0.305054)
			(stroke
				(width 0.1)
				(type default)
			)
			(layer "F.Fab")
		)
		(fp_line
			(start -0.67945 0.3048)
			(end -0.67945 -0.305054)
			(stroke
				(width 0.1)
				(type default)
			)
			(layer "F.Fab")
		)
		(fp_line
			(start -0.12065 -0.305054)
			(end -0.12065 -0.2794)
			(stroke
				(width 0.1)
				(type default)
			)
			(layer "F.Fab")
		)
		(fp_line
			(start -0.12065 -0.2794)
			(end 0.12065 -0.2794)
			(stroke
				(width 0.1)
				(type default)
			)
			(layer "F.Fab")
		)
		(fp_line
			(start -0.12065 0.2794)
			(end -0.12065 0.3048)
			(stroke
				(width 0.1)
				(type default)
			)
			(layer "F.Fab")
		)
		(fp_line
			(start -0.12065 0.3048)
			(end -0.67945 0.3048)
			(stroke
				(width 0.1)
				(type default)
			)
			(layer "F.Fab")
		)
		(fp_line
			(start 0.120396 0.2794)
			(end -0.12065 0.2794)
			(stroke
				(width 0.1)
				(type default)
			)
			(layer "F.Fab")
		)
		(fp_line
			(start 0.120396 0.3048)
			(end 0.120396 0.2794)
			(stroke
				(width 0.1)
				(type default)
			)
			(layer "F.Fab")
		)
		(fp_line
			(start 0.12065 -0.3048)
			(end 0.67945 -0.3048)
			(stroke
				(width 0.1)
				(type default)
			)
			(layer "F.Fab")
		)
		(fp_line
			(start 0.12065 -0.2794)
			(end 0.12065 -0.3048)
			(stroke
				(width 0.1)
				(type default)
			)
			(layer "F.Fab")
		)
		(fp_line
			(start 0.67945 -0.3048)
			(end 0.67945 0.3048)
			(stroke
				(width 0.1)
				(type default)
			)
			(layer "F.Fab")
		)
		(fp_line
			(start 0.67945 0.3048)
			(end 0.120396 0.3048)
			(stroke
				(width 0.1)
				(type default)
			)
			(layer "F.Fab")
		)
		(pad "1" smd circle
			(at -0.40005 0)
			(size 0 0)
			(layers "F.Cu" "F.Mask" "F.Paste")
			(net "SW_P12V_AUX_PVDDIO_P0_FLT")
		)
		(pad "2" smd circle
			(at 0.40005 0)
			(size 0 0)
			(layers "F.Cu" "F.Mask" "F.Paste")
			(net "GND")
		)
	)
)
